# T6G (Grand Teton) — schematic netlist excerpt (pin names and nets, part order shuffled) for the footprints in the layout excerpt that follows; sources: Cadence DE-HDL packaged netlist, KiCad conversion of 04192023_DAF0TMB3IC0_F0TG_MB_C_brd_V02_OCP.brd

PR6603  Q_RES  0 5% CHIP  pkg 0402LF  page 362 : A = GND ; B = P0V9_RETIMER_CPU0_ADDR

Q135  MOSFET_NCH_DUAL  PJT138K IC  pkg SOT363XD  page 124
  S1  = GND
  G1  = GPU_3V3IO_RSVD1
  D2  = GPU_3V3IO_RSVD1_ISO
  S2  = GND
  G2  = GPU_3V3IO_RSVD1_N
  D1  = GPU_3V3IO_RSVD1_N

(kicad_pcb
	(version 20260206)
	(generator "pcbnew")
	(generator_version "10.0")
	(general
		(thickness 1.6)
		(legacy_teardrops no)
	)
	(paper "A4")
	(title_block
		(title "04192023_DAF0TMB3IC0_F0TG_MB_C_brd_V02_OCP.brd")
		(comment 1 "Grand Teton / footprints 2676-2677 of 8354")
	)
	(layers
		(0 "F.Cu" signal "TOP")
		(4 "In1.Cu" signal "GND")
		(6 "In2.Cu" signal "IN1")
		(8 "In3.Cu" signal "GND1")
		(10 "In4.Cu" signal "IN2")
		(12 "In5.Cu" signal "GND2")
		(14 "In6.Cu" signal "IN3")
		(16 "In7.Cu" signal "GND3")
		(18 "In8.Cu" signal "VCC")
		(20 "In9.Cu" signal "VCC1")
		(22 "In10.Cu" signal "GND4")
		(24 "In11.Cu" signal "IN4")
		(26 "In12.Cu" signal "GND5")
		(28 "In13.Cu" signal "IN5")
		(30 "In14.Cu" signal "GND6")
		(32 "In15.Cu" signal "IN6")
		(34 "In16.Cu" signal "GND7")
		(2 "B.Cu" signal "BOTTOM")
		(9 "F.Adhes" user "F.Adhesive")
		(11 "B.Adhes" user "B.Adhesive")
		(13 "F.Paste" user "Package Geometry/Pastemask Top")
		(15 "B.Paste" user "Package Geometry/Pastemask Bottom")
		(5 "F.SilkS" user "Ref Des/Silkscreen Top")
		(7 "B.SilkS" user "Ref Des/Silkscreen Bottom")
		(1 "F.Mask" user "Board Geometry/Soldermask Top")
		(3 "B.Mask" user "Board Geometry/Soldermask Bottom")
		(17 "Dwgs.User" user "User.Drawings")
		(19 "Cmts.User" user "User.Comments")
		(21 "Eco1.User" user "User.Eco1")
		(23 "Eco2.User" user "User.Eco2")
		(25 "Edge.Cuts" user "Board Geometry/Outline")
		(27 "Margin" user)
		(31 "F.CrtYd" user "Package Geometry/Place Bound Top")
		(29 "B.CrtYd" user "Package Geometry/Place Bound Bottom")
		(35 "F.Fab" user "Ref Des/Assembly Top")
		(33 "B.Fab" user "Ref Des/Assembly Bottom")
	)
	(footprint ""
		(layer "F.Cu")
		(at 449.443602 -422.01211 180)
		(property "Reference" "PR6603"
			(at 0 0 180)
			(layer "F.SilkS")
			(hide yes)
			(effects
				(font
					(size 1.27 1.27)
				)
			)
		)
		(property "Value" ""
			(at 0 0 180)
			(layer "F.Fab")
			(effects
				(font
					(size 1.27 1.27)
				)
			)
		)
		(duplicate_pad_numbers_are_jumpers no)
		(fp_line
			(start 0.7874 0.4064)
			(end -0.7874 0.4064)
			(stroke
				(width 0.1524)
				(type default)
			)
			(layer "F.SilkS")
		)
		(fp_line
			(start 0.7874 -0.4064)
			(end 0.7874 0.4064)
			(stroke
				(width 0.1524)
				(type default)
			)
			(layer "F.SilkS")
		)
		(fp_line
			(start -0.7874 0.4064)
			(end -0.7874 -0.4064)
			(stroke
				(width 0.1524)
				(type default)
			)
			(layer "F.SilkS")
		)
		(fp_line
			(start -0.7874 -0.4064)
			(end 0.7874 -0.4064)
			(stroke
				(width 0.1524)
				(type default)
			)
			(layer "F.SilkS")
		)
		(fp_line
			(start 0.67945 0.3048)
			(end 0.120396 0.3048)
			(stroke
				(width 0.1)
				(type default)
			)
			(layer "F.Fab")
		)
		(fp_line
			(start 0.67945 -0.3048)
			(end 0.67945 0.3048)
			(stroke
				(width 0.1)
				(type default)
			)
			(layer "F.Fab")
		)
		(fp_line
			(start 0.12065 -0.2794)
			(end 0.12065 -0.3048)
			(stroke
				(width 0.1)
				(type default)
			)
			(layer "F.Fab")
		)
		(fp_line
			(start 0.12065 -0.3048)
			(end 0.67945 -0.3048)
			(stroke
				(width 0.1)
				(type default)
			)
			(layer "F.Fab")
		)
		(fp_line
			(start 0.120396 0.3048)
			(end 0.120396 0.2794)
			(stroke
				(width 0.1)
				(type default)
			)
			(layer "F.Fab")
		)
		(fp_line
			(start 0.120396 0.2794)
			(end -0.12065 0.2794)
			(stroke
				(width 0.1)
				(type default)
			)
			(layer "F.Fab")
		)
		(fp_line
			(start -0.12065 0.3048)
			(end -0.67945 0.3048)
			(stroke
				(width 0.1)
				(type default)
			)
			(layer "F.Fab")
		)
		(fp_line
			(start -0.12065 0.2794)
			(end -0.12065 0.3048)
			(stroke
				(width 0.1)
				(type default)
			)
			(layer "F.Fab")
		)
		(fp_line
			(start -0.12065 -0.2794)
			(end 0.12065 -0.2794)
			(stroke
				(width 0.1)
				(type default)
			)
			(layer "F.Fab")
		)
		(fp_line
			(start -0.12065 -0.305054)
			(end -0.12065 -0.2794)
			(stroke
				(width 0.1)
				(type default)
			)
			(layer "F.Fab")
		)
		(fp_line
			(start -0.67945 0.3048)
			(end -0.67945 -0.305054)
			(stroke
				(width 0.1)
				(type default)
			)
			(layer "F.Fab")
		)
		(fp_line
			(start -0.67945 -0.305054)
			(end -0.12065 -0.305054)
			(stroke
				(width 0.1)
				(type default)
			)
			(layer "F.Fab")
		)
		(pad "1" smd circle
			(at -0.40005 0 180)
			(size 0 0)
			(layers "F.Cu" "F.Mask" "F.Paste")
			(net "GND")
		)
		(pad "2" smd circle
			(at 0.40005 0 180)
			(size 0 0)
			(layers "F.Cu" "F.Mask" "F.Paste")
			(net "P0V9_RETIMER_CPU0_ADDR")
		)
	)
	(footprint ""
		(layer "F.Cu")
		(at 423.35704 -435.436772)
		(property "Reference" "Q135"
			(at -1.4224 -1.768348 0)
			(unlocked yes)
			(layer "F.SilkS")
			(effects
				(font
					(size 0.7874 0.5842)
					(thickness 0.1524)
				)
				(justify left)
			)
		)
		(property "Value" ""
			(at 0 0 0)
			(layer "F.Fab")
			(effects
				(font
					(size 1.27 1.27)
				)
			)
		)
		(duplicate_pad_numbers_are_jumpers no)
		(fp_line
			(start -1.332738 -1.100074)
			(end -0.4826 -1.100074)
			(stroke
				(width 0.1524)
				(type default)
			)
			(layer "F.SilkS")
		)
		(fp_line
			(start -1.332738 1.100074)
			(end -1.332738 -1.100074)
			(stroke
				(width 0.1524)
				(type default)
			)
			(layer "F.SilkS")
		)
		(fp_line
			(start -0.4826 -1.100074)
			(end 0 -0.541274)
			(stroke
				(width 0.1524)
				(type default)
			)
			(layer "F.SilkS")
		)
		(fp_line
			(start 0 -0.541274)
			(end 0.4826 -1.100074)
			(stroke
				(width 0.1524)
				(type default)
			)
			(layer "F.SilkS")
		)
		(fp_line
			(start 0.4826 -1.100074)
			(end 1.332738 -1.100074)
			(stroke
				(width 0.1524)
				(type default)
			)
			(layer "F.SilkS")
		)
		(fp_line
			(start 1.332738 -1.100074)
			(end 1.332738 1.100074)
			(stroke
				(width 0.1524)
				(type default)
			)
			(layer "F.SilkS")
		)
		(fp_line
			(start 1.332738 1.100074)
			(end -1.332738 1.100074)
			(stroke
				(width 0.1524)
				(type default)
			)
			(layer "F.SilkS")
		)
		(fp_poly
			(pts
				(xy -1.467104 -1.206246) (xy -2.16916 -0.855218) (xy -2.16916 -1.557274)
			)
			(stroke
				(width 0)
				(type default)
			)
			(fill yes)
			(layer "F.SilkS")
		)
		(fp_line
			(start -0.674878 -1.100074)
			(end 0.674878 -1.100074)
			(stroke
				(width 0.1)
				(type default)
			)
			(layer "F.Fab")
		)
		(fp_line
			(start -0.674878 1.100074)
			(end -0.674878 -1.100074)
			(stroke
				(width 0.1)
				(type default)
			)
			(layer "F.Fab")
		)
		(fp_line
			(start 0.674878 -1.100074)
			(end 0.674878 1.100074)
			(stroke
				(width 0.1)
				(type default)
			)
			(layer "F.Fab")
		)
		(fp_line
			(start 0.674878 1.100074)
			(end -0.674878 1.100074)
			(stroke
				(width 0.1)
				(type default)
			)
			(layer "F.Fab")
		)
		(fp_poly
			(pts
				(xy -2.2352 -0.298958) (xy -2.2352 -1.001014) (xy -1.533144 -0.649986)
			)
			(stroke
				(width 0)
				(type default)
			)
			(fill yes)
			(layer "F.Fab")
		)
		(pad "1" smd rect
			(at -0.94996 -0.649986 90)
			(size 0.4318 0.508)
			(layers "F.Cu" "F.Mask" "F.Paste")
			(net "GND")
		)
		(pad "2" smd rect
			(at -0.94996 0 90)
			(size 0.4318 0.508)
			(layers "F.Cu" "F.Mask" "F.Paste")
			(net "GPU_3V3IO_RSVD1")
		)
		(pad "3" smd rect
			(at -0.94996 0.649986 90)
			(size 0.4318 0.508)
			(layers "F.Cu" "F.Mask" "F.Paste")
			(net "GPU_3V3IO_RSVD1_ISO")
		)
		(pad "4" smd rect
			(at 0.94996 0.649986 90)
			(size 0.4318 0.508)
			(layers "F.Cu" "F.Mask" "F.Paste")
			(net "GND")
		)
		(pad "5" smd rect
			(at 0.94996 0 90)
			(size 0.4318 0.508)
			(layers "F.Cu" "F.Mask" "F.Paste")
			(net "GPU_3V3IO_RSVD1_N")
		)
		(pad "6" smd rect
			(at 0.94996 -0.649986 90)
			(size 0.4318 0.508)
			(layers "F.Cu" "F.Mask" "F.Paste")
			(net "GPU_3V3IO_RSVD1_N")
		)
	)
)
